(kicad_pcb
	(version 20260206)
	(generator "pcbnew")
	(generator_version "10.0")
	(general
		(thickness 1.6)
		(legacy_teardrops no)
	)
	(paper "A4")
	(title_block
		(title "01162023_DA0F0TEBIF0_F0T_Expander_BD_F_brd_V02_OCP.brd")
		(comment 1 "Grand Teton / footprints 6269-6274 of 9728")
	)
	(layers
		(0 "F.Cu" signal "TOP")
		(4 "In1.Cu" signal "GND")
		(6 "In2.Cu" signal "VCC")
		(8 "In3.Cu" signal "VCC1")
		(10 "In4.Cu" signal "GND1")
		(12 "In5.Cu" signal "IN1")
		(14 "In6.Cu" signal "GND2")
		(16 "In7.Cu" signal "IN2")
		(18 "In8.Cu" signal "GND3")
		(20 "In9.Cu" signal "IN3")
		(22 "In10.Cu" signal "GND4")
		(24 "In11.Cu" signal "IN4")
		(26 "In12.Cu" signal "GND5")
		(28 "In13.Cu" signal "IN5")
		(30 "In14.Cu" signal "GND6")
		(32 "In15.Cu" signal "IN6")
		(34 "In16.Cu" signal "GND7")
		(2 "B.Cu" signal "BOTTOM")
		(9 "F.Adhes" user "F.Adhesive")
		(11 "B.Adhes" user "B.Adhesive")
		(13 "F.Paste" user "Package Geometry/Pastemask Top")
		(15 "B.Paste" user "Package Geometry/Pastemask Bottom")
		(5 "F.SilkS" user "Ref Des/Silkscreen Top")
		(7 "B.SilkS" user "Ref Des/Silkscreen Bottom")
		(1 "F.Mask" user "Board Geometry/Soldermask Top")
		(3 "B.Mask" user "Board Geometry/Soldermask Bottom")
		(17 "Dwgs.User" user "User.Drawings")
		(19 "Cmts.User" user "User.Comments")
		(21 "Eco1.User" user "User.Eco1")
		(23 "Eco2.User" user "User.Eco2")
		(25 "Edge.Cuts" user "Board Geometry/Outline")
		(27 "Margin" user)
		(31 "F.CrtYd" user "Package Geometry/Place Bound Top")
		(29 "B.CrtYd" user "Package Geometry/Place Bound Bottom")
		(35 "F.Fab" user "Ref Des/Assembly Top")
		(33 "B.Fab" user "Ref Des/Assembly Bottom")
	)
	(footprint ""
		(layer "F.Cu")
		(at 22.647148 -54.3941)
		(property "Reference" "PU30"
			(at -1.670812 3.085592 0)
			(unlocked yes)
			(layer "F.SilkS")
			(effects
				(font
					(size 0.7874 0.5842)
					(thickness 0.1524)
				)
				(justify left)
			)
		)
		(property "Value" ""
			(at 0 0 0)
			(layer "F.Fab")
			(effects
				(font
					(size 1.27 1.27)
				)
			)
		)
		(duplicate_pad_numbers_are_jumpers no)
		(fp_line
			(start -1.943608 -1.549908)
			(end 1.943608 -1.549908)
			(stroke
				(width 0.1524)
				(type default)
			)
			(layer "F.SilkS")
		)
		(fp_line
			(start -1.943608 1.549908)
			(end -1.943608 -1.549908)
			(stroke
				(width 0.1524)
				(type default)
			)
			(layer "F.SilkS")
		)
		(fp_line
			(start 1.943608 -1.549908)
			(end 1.943608 1.549908)
			(stroke
				(width 0.1524)
				(type default)
			)
			(layer "F.SilkS")
		)
		(fp_line
			(start 1.943608 1.549908)
			(end -1.943608 1.549908)
			(stroke
				(width 0.1524)
				(type default)
			)
			(layer "F.SilkS")
		)
		(fp_poly
			(pts
				(xy -2.019808 -1.549908) (xy -1.257808 -1.549908) (xy -1.257808 -1.880108) (xy -2.019808 -1.880108)
			)
			(stroke
				(width 0)
				(type default)
			)
			(fill yes)
			(layer "F.SilkS")
		)
		(fp_line
			(start -1.549908 -1.549908)
			(end 1.549908 -1.549908)
			(stroke
				(width 0.1)
				(type default)
			)
			(layer "F.Fab")
		)
		(fp_line
			(start -1.549908 1.549908)
			(end -1.549908 -1.549908)
			(stroke
				(width 0.1)
				(type default)
			)
			(layer "F.Fab")
		)
		(fp_line
			(start 1.549908 -1.549908)
			(end 1.549908 1.549908)
			(stroke
				(width 0.1)
				(type default)
			)
			(layer "F.Fab")
		)
		(fp_line
			(start 1.549908 1.549908)
			(end -1.549908 1.549908)
			(stroke
				(width 0.1)
				(type default)
			)
			(layer "F.Fab")
		)
		(fp_poly
			(pts
				(xy -2.019808 -1.549908) (xy -1.257808 -1.549908) (xy -1.257808 -1.880108) (xy -2.019808 -1.880108)
			)
			(stroke
				(width 0)
				(type default)
			)
			(fill yes)
			(layer "F.Fab")
		)
		(pad "1" smd rect
			(at -1.500124 -1.249934 270)
			(size 0.2794 0.6096)
			(layers "F.Cu" "F.Mask" "F.Paste")
			(net "P12V_SSD0_R")
		)
		(pad "2" smd rect
			(at -1.500124 -0.750062 270)
			(size 0.2794 0.6096)
			(layers "F.Cu" "F.Mask" "F.Paste")
			(net "P12V_SSD0_R")
		)
		(pad "3" smd rect
			(at -1.500124 -0.249936 270)
			(size 0.2794 0.6096)
			(layers "F.Cu" "F.Mask" "F.Paste")
			(net "P12V_SSD0_R")
		)
		(pad "4" smd rect
			(at -1.500124 0.249936 270)
			(size 0.2794 0.6096)
			(layers "F.Cu" "F.Mask" "F.Paste")
			(net "P12V_SSD0_R")
		)
		(pad "5" smd rect
			(at -1.500124 0.750062 270)
			(size 0.2794 0.6096)
			(layers "F.Cu" "F.Mask" "F.Paste")
			(net "P12V_SSD0_R")
		)
		(pad "6" smd rect
			(at -1.500124 1.249934 270)
			(size 0.2794 0.6096)
			(layers "F.Cu" "F.Mask" "F.Paste")
			(net "GND")
		)
		(pad "7" smd rect
			(at 1.500124 1.249934 270)
			(size 0.2794 0.6096)
			(layers "F.Cu" "F.Mask" "F.Paste")
			(net "P12V_SSD0_SS")
		)
		(pad "8" smd rect
			(at 1.500124 0.750062 270)
			(size 0.2794 0.6096)
			(layers "F.Cu" "F.Mask" "F.Paste")
			(net "PWRGD_P12V_SSD0")
		)
		(pad "9" smd rect
			(at 1.500124 0.249936 270)
			(size 0.2794 0.6096)
			(layers "F.Cu" "F.Mask" "F.Paste")
			(net "P12V_SSD0_OCP")
		)
		(pad "10" smd rect
			(at 1.500124 -0.249936 270)
			(size 0.2794 0.6096)
			(layers "F.Cu" "F.Mask" "F.Paste")
			(net "P5V_AUX")
		)
		(pad "11" smd rect
			(at 1.500124 -0.750062 270)
			(size 0.2794 0.6096)
			(layers "F.Cu" "F.Mask" "F.Paste")
			(net "SSD0_PWR_EN_R")
		)
		(pad "12" smd rect
			(at 1.500124 -1.249934 270)
			(size 0.2794 0.6096)
			(layers "F.Cu" "F.Mask" "F.Paste")
			(net "P12V_AUX")
		)
		(pad "13" smd rect
			(at 0 0)
			(size 1.9812 2.7178)
			(layers "F.Cu" "F.Mask" "F.Paste")
			(net "P12V_AUX")
		)
		(zone
			(layer "F.Cu")
			(hatch none 0.5)
			(connect_pads
				(clearance 0)
			)
			(min_thickness 0.25)
			(keepout
				(tracks not_allowed)
				(vias allowed)
				(pads allowed)
				(copperpour not_allowed)
				(footprints allowed)
			)
			(placement
				(enabled no)
				(sheetname "")
			)
			(fill
				(thermal_gap 0.5)
				(thermal_bridge_width 0.5)
				(island_removal_mode 0)
			)
			(polygon
				(pts
					(xy 23.790148 -55.9435) (xy 23.790148 -55.8165) (xy 23.790148 -52.8447) (xy 23.790148 -52.844192)
					(xy 21.504148 -52.844192) (xy 21.504148 -52.8447) (xy 21.504148 -52.9717) (xy 21.504148 -54.3941)
					(xy 21.605748 -54.3941) (xy 21.605748 -52.9717) (xy 23.688548 -52.9717) (xy 23.688548 -55.8165)
					(xy 21.605748 -55.8165) (xy 21.605748 -54.4195) (xy 21.504148 -54.4195) (xy 21.504148 -55.8165)
					(xy 21.504148 -55.9435) (xy 21.504148 -55.944008) (xy 23.790148 -55.944008)
				)
			)
		)
	)
	(footprint ""
		(layer "F.Cu")
		(at 95.79229 -31.825184 180)
		(property "Reference" "C92"
			(at 0 0 180)
			(layer "F.SilkS")
			(hide yes)
			(effects
				(font
					(size 1.27 1.27)
				)
			)
		)
		(property "Value" ""
			(at 0 0 180)
			(layer "F.Fab")
			(effects
				(font
					(size 1.27 1.27)
				)
			)
		)
		(duplicate_pad_numbers_are_jumpers no)
		(fp_line
			(start 0.299974 0.150114)
			(end -0.299974 0.150114)
			(stroke
				(width 0.1)
				(type default)
			)
			(layer "F.Fab")
		)
		(fp_line
			(start 0.299974 -0.150114)
			(end 0.299974 0.150114)
			(stroke
				(width 0.1)
				(type default)
			)
			(layer "F.Fab")
		)
		(fp_line
			(start -0.299974 0.150114)
			(end -0.299974 -0.150114)
			(stroke
				(width 0.1)
				(type default)
			)
			(layer "F.Fab")
		)
		(fp_line
			(start -0.299974 -0.150114)
			(end 0.299974 -0.150114)
			(stroke
				(width 0.1)
				(type default)
			)
			(layer "F.Fab")
		)
		(pad "1" smd rect
			(at -0.2667 0 180)
			(size 0.3048 0.381)
			(layers "F.Cu" "F.Mask" "F.Paste")
			(net "P5E_PEX0_STN2_TX_DN<34>")
		)
		(pad "2" smd rect
			(at 0.2667 0 180)
			(size 0.3048 0.381)
			(layers "F.Cu" "F.Mask" "F.Paste")
			(net "P5E_PEX0_STN2_TX_C_DN<34>")
		)
	)
	(footprint ""
		(layer "F.Cu")
		(at 36.2458 -258.463034)
		(property "Reference" "C3045"
			(at 0 0 0)
			(layer "F.SilkS")
			(hide yes)
			(effects
				(font
					(size 1.27 1.27)
				)
			)
		)
		(property "Value" ""
			(at 0 0 0)
			(layer "F.Fab")
			(effects
				(font
					(size 1.27 1.27)
				)
			)
		)
		(duplicate_pad_numbers_are_jumpers no)
		(fp_line
			(start -1.2954 -0.5842)
			(end 1.2954 -0.5842)
			(stroke
				(width 0.1524)
				(type default)
			)
			(layer "F.SilkS")
		)
		(fp_line
			(start -1.2954 0.5842)
			(end -1.2954 -0.5842)
			(stroke
				(width 0.1524)
				(type default)
			)
			(layer "F.SilkS")
		)
		(fp_line
			(start 1.2954 -0.5842)
			(end 1.2954 0.5842)
			(stroke
				(width 0.1524)
				(type default)
			)
			(layer "F.SilkS")
		)
		(fp_line
			(start 1.2954 0.5842)
			(end -1.2954 0.5842)
			(stroke
				(width 0.1524)
				(type default)
			)
			(layer "F.SilkS")
		)
		(fp_line
			(start -1.1938 -0.4064)
			(end -0.8636 -0.4064)
			(stroke
				(width 0.1)
				(type default)
			)
			(layer "F.Fab")
		)
		(fp_line
			(start -1.1938 0.4064)
			(end -1.1938 -0.4064)
			(stroke
				(width 0.1)
				(type default)
			)
			(layer "F.Fab")
		)
		(fp_line
			(start -0.8636 -0.4572)
			(end 0.8636 -0.4572)
			(stroke
				(width 0.1)
				(type default)
			)
			(layer "F.Fab")
		)
		(fp_line
			(start -0.8636 -0.4064)
			(end -0.8636 -0.4572)
			(stroke
				(width 0.1)
				(type default)
			)
			(layer "F.Fab")
		)
		(fp_line
			(start -0.8636 0.4064)
			(end -1.1938 0.4064)
			(stroke
				(width 0.1)
				(type default)
			)
			(layer "F.Fab")
		)
		(fp_line
			(start -0.8636 0.4572)
			(end -0.8636 0.4064)
			(stroke
				(width 0.1)
				(type default)
			)
			(layer "F.Fab")
		)
		(fp_line
			(start 0.8636 -0.4572)
			(end 0.8636 -0.4064)
			(stroke
				(width 0.1)
				(type default)
			)
			(layer "F.Fab")
		)
		(fp_line
			(start 0.8636 -0.4064)
			(end 1.1938 -0.4064)
			(stroke
				(width 0.1)
				(type default)
			)
			(layer "F.Fab")
		)
		(fp_line
			(start 0.8636 0.4064)
			(end 0.8636 0.4572)
			(stroke
				(width 0.1)
				(type default)
			)
			(layer "F.Fab")
		)
		(fp_line
			(start 0.8636 0.4572)
			(end -0.8636 0.4572)
			(stroke
				(width 0.1)
				(type default)
			)
			(layer "F.Fab")
		)
		(fp_line
			(start 1.1938 -0.4064)
			(end 1.1938 0.4064)
			(stroke
				(width 0.1)
				(type default)
			)
			(layer "F.Fab")
		)
		(fp_line
			(start 1.1938 0.4064)
			(end 0.8636 0.4064)
			(stroke
				(width 0.1)
				(type default)
			)
			(layer "F.Fab")
		)
		(pad "1" smd rect
			(at -0.7366 0 270)
			(size 0.7112 0.8128)
			(layers "F.Cu" "F.Mask" "F.Paste")
			(net "PCEPLL5_VDDA18_PEX0")
		)
		(pad "2" smd rect
			(at 0.7366 0 270)
			(size 0.7112 0.8128)
			(layers "F.Cu" "F.Mask" "F.Paste")
			(net "GND")
		)
	)
	(footprint ""
		(layer "F.Cu")
		(at 209.09788 -296.365168 90)
		(property "Reference" "C2757"
			(at 0 0 90)
			(layer "F.SilkS")
			(hide yes)
			(effects
				(font
					(size 1.27 1.27)
				)
			)
		)
		(property "Value" ""
			(at 0 0 90)
			(layer "F.Fab")
			(effects
				(font
					(size 1.27 1.27)
				)
			)
		)
		(duplicate_pad_numbers_are_jumpers no)
		(fp_line
			(start 0.7874 -0.4064)
			(end 0.7874 0.4064)
			(stroke
				(width 0.1524)
				(type default)
			)
			(layer "F.SilkS")
		)
		(fp_line
			(start -0.7874 -0.4064)
			(end 0.7874 -0.4064)
			(stroke
				(width 0.1524)
				(type default)
			)
			(layer "F.SilkS")
		)
		(fp_line
			(start 0.7874 0.4064)
			(end -0.7874 0.4064)
			(stroke
				(width 0.1524)
				(type default)
			)
			(layer "F.SilkS")
		)
		(fp_line
			(start -0.7874 0.4064)
			(end -0.7874 -0.4064)
			(stroke
				(width 0.1524)
				(type default)
			)
			(layer "F.SilkS")
		)
		(fp_line
			(start -0.12065 -0.305054)
			(end -0.12065 -0.2794)
			(stroke
				(width 0.1)
				(type default)
			)
			(layer "F.Fab")
		)
		(fp_line
			(start -0.67945 -0.305054)
			(end -0.12065 -0.305054)
			(stroke
				(width 0.1)
				(type default)
			)
			(layer "F.Fab")
		)
		(fp_line
			(start 0.67945 -0.3048)
			(end 0.67945 0.3048)
			(stroke
				(width 0.1)
				(type default)
			)
			(layer "F.Fab")
		)
		(fp_line
			(start 0.12065 -0.3048)
			(end 0.67945 -0.3048)
			(stroke
				(width 0.1)
				(type default)
			)
			(layer "F.Fab")
		)
		(fp_line
			(start 0.12065 -0.2794)
			(end 0.12065 -0.3048)
			(stroke
				(width 0.1)
				(type default)
			)
			(layer "F.Fab")
		)
		(fp_line
			(start -0.12065 -0.2794)
			(end 0.12065 -0.2794)
			(stroke
				(width 0.1)
				(type default)
			)
			(layer "F.Fab")
		)
		(fp_line
			(start 0.120396 0.2794)
			(end -0.12065 0.2794)
			(stroke
				(width 0.1)
				(type default)
			)
			(layer "F.Fab")
		)
		(fp_line
			(start -0.12065 0.2794)
			(end -0.12065 0.3048)
			(stroke
				(width 0.1)
				(type default)
			)
			(layer "F.Fab")
		)
		(fp_line
			(start 0.67945 0.3048)
			(end 0.120396 0.3048)
			(stroke
				(width 0.1)
				(type default)
			)
			(layer "F.Fab")
		)
		(fp_line
			(start 0.120396 0.3048)
			(end 0.120396 0.2794)
			(stroke
				(width 0.1)
				(type default)
			)
			(layer "F.Fab")
		)
		(fp_line
			(start -0.12065 0.3048)
			(end -0.67945 0.3048)
			(stroke
				(width 0.1)
				(type default)
			)
			(layer "F.Fab")
		)
		(fp_line
			(start -0.67945 0.3048)
			(end -0.67945 -0.305054)
			(stroke
				(width 0.1)
				(type default)
			)
			(layer "F.Fab")
		)
		(pad "1" smd circle
			(at -0.40005 0 90)
			(size 0 0)
			(layers "F.Cu" "F.Mask" "F.Paste")
			(net "GND")
		)
		(pad "2" smd circle
			(at 0.40005 0 90)
			(size 0 0)
			(layers "F.Cu" "F.Mask" "F.Paste")
			(net "P1V8_PEX")
		)
	)
	(footprint ""
		(layer "F.Cu")
		(at 239.333024 -254.18542 -90)
		(property "Reference" "C4341"
			(at 0 0 270)
			(layer "F.SilkS")
			(hide yes)
			(effects
				(font
					(size 1.27 1.27)
				)
			)
		)
		(property "Value" ""
			(at 0 0 270)
			(layer "F.Fab")
			(effects
				(font
					(size 1.27 1.27)
				)
			)
		)
		(duplicate_pad_numbers_are_jumpers no)
		(fp_line
			(start -1.2954 0.5842)
			(end -1.2954 -0.5842)
			(stroke
				(width 0.1524)
				(type default)
			)
			(layer "F.SilkS")
		)
		(fp_line
			(start 1.2954 0.5842)
			(end -1.2954 0.5842)
			(stroke
				(width 0.1524)
				(type default)
			)
			(layer "F.SilkS")
		)
		(fp_line
			(start -1.2954 -0.5842)
			(end 1.2954 -0.5842)
			(stroke
				(width 0.1524)
				(type default)
			)
			(layer "F.SilkS")
		)
		(fp_line
			(start 1.2954 -0.5842)
			(end 1.2954 0.5842)
			(stroke
				(width 0.1524)
				(type default)
			)
			(layer "F.SilkS")
		)
		(fp_line
			(start -0.8636 0.4572)
			(end -0.8636 0.4064)
			(stroke
				(width 0.1)
				(type default)
			)
			(layer "F.Fab")
		)
		(fp_line
			(start 0.8636 0.4572)
			(end -0.8636 0.4572)
			(stroke
				(width 0.1)
				(type default)
			)
			(layer "F.Fab")
		)
		(fp_line
			(start -1.1938 0.4064)
			(end -1.1938 -0.4064)
			(stroke
				(width 0.1)
				(type default)
			)
			(layer "F.Fab")
		)
		(fp_line
			(start -0.8636 0.4064)
			(end -1.1938 0.4064)
			(stroke
				(width 0.1)
				(type default)
			)
			(layer "F.Fab")
		)
		(fp_line
			(start 0.8636 0.4064)
			(end 0.8636 0.4572)
			(stroke
				(width 0.1)
				(type default)
			)
			(layer "F.Fab")
		)
		(fp_line
			(start 1.1938 0.4064)
			(end 0.8636 0.4064)
			(stroke
				(width 0.1)
				(type default)
			)
			(layer "F.Fab")
		)
		(fp_line
			(start -1.1938 -0.4064)
			(end -0.8636 -0.4064)
			(stroke
				(width 0.1)
				(type default)
			)
			(layer "F.Fab")
		)
		(fp_line
			(start -0.8636 -0.4064)
			(end -0.8636 -0.4572)
			(stroke
				(width 0.1)
				(type default)
			)
			(layer "F.Fab")
		)
		(fp_line
			(start 0.8636 -0.4064)
			(end 1.1938 -0.4064)
			(stroke
				(width 0.1)
				(type default)
			)
			(layer "F.Fab")
		)
		(fp_line
			(start 1.1938 -0.4064)
			(end 1.1938 0.4064)
			(stroke
				(width 0.1)
				(type default)
			)
			(layer "F.Fab")
		)
		(fp_line
			(start -0.8636 -0.4572)
			(end 0.8636 -0.4572)
			(stroke
				(width 0.1)
				(type default)
			)
			(layer "F.Fab")
		)
		(fp_line
			(start 0.8636 -0.4572)
			(end 0.8636 -0.4064)
			(stroke
				(width 0.1)
				(type default)
			)
			(layer "F.Fab")
		)
		(pad "1" smd rect
			(at -0.7366 0 180)
			(size 0.7112 0.8128)
			(layers "F.Cu" "F.Mask" "F.Paste")
			(net "P1V25_SERDES_VDDPLL_PEX2_C3")
		)
		(pad "2" smd rect
			(at 0.7366 0 180)
			(size 0.7112 0.8128)
			(layers "F.Cu" "F.Mask" "F.Paste")
			(net "GND")
		)
	)
	(footprint ""
		(layer "F.Cu")
		(at 142.710662 -18.61439 90)
		(property "Reference" "U130"
			(at -1.49479 2.273808 90)
			(unlocked yes)
			(layer "F.SilkS")
			(effects
				(font
					(size 0.7874 0.5842)
					(thickness 0.1524)
				)
				(justify left)
			)
		)
		(property "Value" ""
			(at 0 0 90)
			(layer "F.Fab")
			(effects
				(font
					(size 1.27 1.27)
				)
			)
		)
		(duplicate_pad_numbers_are_jumpers no)
		(fp_line
			(start 1.463548 -1.549908)
			(end 1.463548 1.549908)
			(stroke
				(width 0.1524)
				(type default)
			)
			(layer "F.SilkS")
		)
		(fp_line
			(start 0.762 -1.549908)
			(end 1.463548 -1.549908)
			(stroke
				(width 0.1524)
				(type default)
			)
			(layer "F.SilkS")
		)
		(fp_line
			(start -0.787908 -1.549908)
			(end 0 -0.762)
			(stroke
				(width 0.1524)
				(type default)
			)
			(layer "F.SilkS")
		)
		(fp_line
			(start -1.463548 -1.549908)
			(end -0.787908 -1.549908)
			(stroke
				(width 0.1524)
				(type default)
			)
			(layer "F.SilkS")
		)
		(fp_line
			(start 0 -0.762)
			(end 0.762 -1.549908)
			(stroke
				(width 0.1524)
				(type default)
			)
			(layer "F.SilkS")
		)
		(fp_line
			(start 1.463548 1.549908)
			(end -1.463548 1.549908)
			(stroke
				(width 0.1524)
				(type default)
			)
			(layer "F.SilkS")
		)
		(fp_line
			(start -1.463548 1.549908)
			(end -1.463548 -1.549908)
			(stroke
				(width 0.1524)
				(type default)
			)
			(layer "F.SilkS")
		)
		(fp_poly
			(pts
				(xy -3.4798 -1.359916) (xy -2.86004 -1.050036) (xy -3.4798 -0.740156)
			)
			(stroke
				(width 0)
				(type default)
			)
			(fill yes)
			(layer "F.SilkS")
		)
		(fp_line
			(start 1.549908 -1.549908)
			(end 1.549908 1.549908)
			(stroke
				(width 0.1)
				(type default)
			)
			(layer "F.Fab")
		)
		(fp_line
			(start -1.549908 -1.549908)
			(end 1.549908 -1.549908)
			(stroke
				(width 0.1)
				(type default)
			)
			(layer "F.Fab")
		)
		(fp_line
			(start 1.549908 1.549908)
			(end -1.549908 1.549908)
			(stroke
				(width 0.1)
				(type default)
			)
			(layer "F.Fab")
		)
		(fp_line
			(start -1.549908 1.549908)
			(end -1.549908 -1.549908)
			(stroke
				(width 0.1)
				(type default)
			)
			(layer "F.Fab")
		)
		(fp_poly
			(pts
				(xy -3.4798 -1.359916) (xy -2.86004 -1.050036) (xy -3.4798 -0.740156)
			)
			(stroke
				(width 0)
				(type default)
			)
			(fill yes)
			(layer "F.Fab")
		)
		(pad "1" smd rect
			(at -2.175002 -1.050036 180)
			(size 0.6096 1.1684)
			(layers "F.Cu" "F.Mask" "F.Paste")
			(net "P3V3_SSD4")
		)
		(pad "2" smd rect
			(at -2.175002 -0.32512 180)
			(size 0.4318 1.1684)
			(layers "F.Cu" "F.Mask" "F.Paste")
			(net "SMB_ISO_SSD4_SCL")
		)
		(pad "3" smd rect
			(at -2.175002 0.32512 180)
			(size 0.4318 1.1684)
			(layers "F.Cu" "F.Mask" "F.Paste")
			(net "SMB_ISO_SSD4_SDA")
		)
		(pad "4" smd rect
			(at -2.175002 1.050036 180)
			(size 0.6096 1.1684)
			(layers "F.Cu" "F.Mask" "F.Paste")
			(net "GND")
		)
		(pad "5" smd rect
			(at 2.175002 1.050036 180)
			(size 0.6096 1.1684)
			(layers "F.Cu" "F.Mask" "F.Paste")
			(net "SMB_SSD4_ISO_EN")
		)
		(pad "6" smd rect
			(at 2.175002 0.32512 180)
			(size 0.4318 1.1684)
			(layers "F.Cu" "F.Mask" "F.Paste")
			(net "SMB_BIC_I2C9_MUX0_SSD4_R_SDA")
		)
		(pad "7" smd rect
			(at 2.175002 -0.32512 180)
			(size 0.4318 1.1684)
			(layers "F.Cu" "F.Mask" "F.Paste")
			(net "SMB_BIC_I2C9_MUX0_SSD4_R_SCL")
		)
		(pad "8" smd rect
			(at 2.175002 -1.050036 180)
			(size 0.6096 1.1684)
			(layers "F.Cu" "F.Mask" "F.Paste")
			(net "P3V3_AUX")
		)
	)
)
